FILE_TYPE = MACRO_DRAWING;
SET COLOR_WIRE YELLOW;
SET COLOR_PROP MONO;
SET COLOR_DOT WHITE;
SET COLOR_ARC YELLOW;
SET COLOR_BODY GREEN;
SET COLOR_NOTE MONO;
SET PROP_DISPLAY VALUE;
SET PAGE_NUMBER P137;
FORCEADD RES..1
R 1
(325 3450);
FORCEPROP 1 LAST PATH I11
R 1
J 0
(175 3400);
DISPLAY 1.319149 (175 3400);
PAINT GREEN (175 3400);
DISPLAY INVISIBLE (175 3400);
FORCEPROP 2 LAST CDS_LIB mstr_discrete
R 1
J 0
(325 3450);
PAINT ORANGE (325 3450);
DISPLAY INVISIBLE (325 3450);
FORCEPROP 2 LAST BOM_COST SB
J 0
(375 3650);
PAINT ORANGE (375 3650);
DISPLAY INVISIBLE (375 3650);
FORCEPROP 2 LAST CDS_SEC 1
J 0
(375 3650);
DISPLAY 1.404255 (375 3650);
PAINT ORANGE (375 3650);
DISPLAY INVISIBLE (375 3650);
FORCEPROP 2 LAST $SEC 1
J 0
(375 3650);
DISPLAY 0.936170 (375 3650);
PAINT MONO (375 3650);
DISPLAY INVISIBLE (375 3650);
FORCEPROP 2 LAST CDS_LOCATION R7C11
J 0
(375 3600);
DISPLAY 0.617021 (375 3600);
PAINT AQUA (375 3600);
DISPLAY INVISIBLE (375 3600);
FORCEPROP 2 LAST ROOM SB
J 0
(375 3650);
PAINT ORANGE (375 3650);
DISPLAY INVISIBLE (375 3650);
FORCEPROP 1 LASTPIN (325 3350) $PN 1
R 1
J 0
(313 3362);
DISPLAY 0.617021 (313 3362);
PAINT MONO (313 3362);
FORCEPROP 1 LASTPIN (325 3550) $PN 2
R 1
J 0
(313 3512);
DISPLAY 0.617021 (313 3512);
PAINT MONO (313 3512);
FORCEPROP 1 LAST WATTAGE 1/16W
J 2
(550 3450);
DISPLAY 0.617021 (550 3450);
PAINT SKYBLUE (550 3450);
FORCEPROP 1 LAST PACK_TYPE 0402
J 0
(375 3300);
DISPLAY 0.617021 (375 3300);
PAINT SKYBLUE (375 3300);
FORCEPROP 1 LAST TOLERANCE 1%
J 0
(375 3500);
DISPLAY 0.617021 (375 3500);
PAINT SKYBLUE (375 3500);
FORCEPROP 1 LAST VALUE 1.0M
J 2
(525 3550);
DISPLAY 0.617021 (525 3550);
PAINT SKYBLUE (525 3550);
FORCEPROP 1 LAST PART_NUMBER G21796-021
J 0
(375 3350);
DISPLAY 0.617021 (375 3350);
PAINT BLUE (375 3350);
FORCEPROP 1 LAST LOCATION R7C11
J 0
(375 3600);
DISPLAY 0.617021 (375 3600);
PAINT AQUA (375 3600);
FORCEPROP 1 LAST MATERIAL EMPTY
J 0
(375 3400);
DISPLAY 0.617021 (375 3400);
PAINT RED (375 3400);
FORCEADD OFFPAGE..5
(-3625 3725);
FORCEPROP 2 LAST $XR0 143 
J 0
(-3880 3725);
DISPLAY 0.638298 (-3880 3725);
PAINT MONO (-3880 3725);
FORCEPROP 1 LAST COMMENT_BODY TRUE
J 0
(-3525 3650);
DISPLAY 0.872340 (-3525 3650);
PAINT GREEN (-3525 3650);
DISPLAY INVISIBLE (-3525 3650);
FORCEPROP 1 LAST OFFPAGE TRUE
J 0
(-3300 3600);
DISPLAY 0.872340 (-3300 3600);
PAINT GREEN (-3300 3600);
DISPLAY INVISIBLE (-3300 3600);
FORCEPROP 2 LAST PATH I123
J 0
(-3575 3800);
DISPLAY 1.021277 (-3575 3800);
PAINT ORANGE (-3575 3800);
DISPLAY INVISIBLE (-3575 3800);
FORCEPROP 2 LAST $XRERR ?
J 0
(-4024 3725);
DISPLAY 0.638298 (-4024 3725);
PAINT MONO (-4024 3725);
DISPLAY INVISIBLE (-4024 3725);
FORCEPROP 2 LAST $XRERR ?
J 0
(-4024 3725);
DISPLAY 0.638298 (-4024 3725);
PAINT MONO (-4024 3725);
DISPLAY INVISIBLE (-4024 3725);
FORCEPROP 2 LAST $XRERR ?
J 0
(-4024 3725);
DISPLAY 0.638298 (-4024 3725);
PAINT MONO (-4024 3725);
DISPLAY INVISIBLE (-4024 3725);
FORCEPROP 2 LAST $XRERR ?
J 0
(-4024 3725);
DISPLAY 0.638298 (-4024 3725);
PAINT MONO (-4024 3725);
DISPLAY INVISIBLE (-4024 3725);
FORCEPROP 2 LAST $XRERR ?
J 0
(-4024 3725);
DISPLAY 0.638298 (-4024 3725);
PAINT MONO (-4024 3725);
DISPLAY INVISIBLE (-4024 3725);
FORCEPROP 2 LAST $XRERR ?
J 0
(-4024 3725);
DISPLAY 0.638298 (-4024 3725);
PAINT MONO (-4024 3725);
DISPLAY INVISIBLE (-4024 3725);
FORCEPROP 2 LAST CDS_LIB mstr_standard
J 0
(-3625 3725);
PAINT ORANGE (-3625 3725);
DISPLAY INVISIBLE (-3625 3725);
FORCEPROP 2 LAST $XRERR ?
J 0
(-4024 3725);
DISPLAY 0.638298 (-4024 3725);
PAINT MONO (-4024 3725);
DISPLAY INVISIBLE (-4024 3725);
FORCEPROP 2 LAST $XRERR ?
J 0
(-4024 3725);
DISPLAY 0.638298 (-4024 3725);
PAINT MONO (-4024 3725);
DISPLAY INVISIBLE (-4024 3725);
FORCEPROP 2 LAST $XRERR ?
J 0
(-4024 3725);
DISPLAY 0.638298 (-4024 3725);
PAINT MONO (-4024 3725);
DISPLAY INVISIBLE (-4024 3725);
FORCEPROP 2 LAST $XRERR ?
J 0
(-4024 3725);
DISPLAY 0.638298 (-4024 3725);
PAINT MONO (-4024 3725);
DISPLAY INVISIBLE (-4024 3725);
FORCEPROP 2 LAST $XRERR ?
J 0
(-4024 3725);
DISPLAY 0.638298 (-4024 3725);
PAINT MONO (-4024 3725);
DISPLAY INVISIBLE (-4024 3725);
FORCEPROP 2 LAST $XRERR ?
J 0
(-4024 3725);
DISPLAY 0.638298 (-4024 3725);
PAINT MONO (-4024 3725);
DISPLAY INVISIBLE (-4024 3725);
FORCEPROP 2 LAST $XR1 ?
J 0
(-4000 3725);
DISPLAY 0.638298 (-4000 3725);
PAINT MONO (-4000 3725);
FORCEADD OFFPAGE..5
(-3625 3675);
FORCEPROP 1 LAST COMMENT_BODY TRUE
J 0
(-3525 3600);
DISPLAY 0.872340 (-3525 3600);
PAINT GREEN (-3525 3600);
DISPLAY INVISIBLE (-3525 3600);
FORCEPROP 1 LAST OFFPAGE TRUE
J 0
(-3300 3550);
DISPLAY 0.872340 (-3300 3550);
PAINT GREEN (-3300 3550);
DISPLAY INVISIBLE (-3300 3550);
FORCEPROP 2 LAST PATH I124
J 0
(-3575 3750);
DISPLAY 1.021277 (-3575 3750);
PAINT ORANGE (-3575 3750);
DISPLAY INVISIBLE (-3575 3750);
FORCEPROP 2 LAST $XRERR ?
J 0
(-4024 3675);
DISPLAY 0.638298 (-4024 3675);
PAINT MONO (-4024 3675);
DISPLAY INVISIBLE (-4024 3675);
FORCEPROP 2 LAST $XRERR ?
J 0
(-4024 3675);
DISPLAY 0.638298 (-4024 3675);
PAINT MONO (-4024 3675);
DISPLAY INVISIBLE (-4024 3675);
FORCEPROP 2 LAST $XRERR ?
J 0
(-4024 3675);
DISPLAY 0.638298 (-4024 3675);
PAINT MONO (-4024 3675);
DISPLAY INVISIBLE (-4024 3675);
FORCEPROP 2 LAST $XRERR ?
J 0
(-4024 3675);
DISPLAY 0.638298 (-4024 3675);
PAINT MONO (-4024 3675);
DISPLAY INVISIBLE (-4024 3675);
FORCEPROP 2 LAST $XRERR ?
J 0
(-4024 3675);
DISPLAY 0.638298 (-4024 3675);
PAINT MONO (-4024 3675);
DISPLAY INVISIBLE (-4024 3675);
FORCEPROP 2 LAST $XRERR ?
J 0
(-4024 3675);
DISPLAY 0.638298 (-4024 3675);
PAINT MONO (-4024 3675);
DISPLAY INVISIBLE (-4024 3675);
FORCEPROP 2 LAST CDS_LIB mstr_standard
J 0
(-3625 3675);
PAINT ORANGE (-3625 3675);
DISPLAY INVISIBLE (-3625 3675);
FORCEPROP 2 LAST $XRERR ?
J 0
(-4024 3675);
DISPLAY 0.638298 (-4024 3675);
PAINT MONO (-4024 3675);
DISPLAY INVISIBLE (-4024 3675);
FORCEPROP 2 LAST $XRERR ?
J 0
(-4024 3675);
DISPLAY 0.638298 (-4024 3675);
PAINT MONO (-4024 3675);
DISPLAY INVISIBLE (-4024 3675);
FORCEPROP 2 LAST $XRERR ?
J 0
(-4024 3675);
DISPLAY 0.638298 (-4024 3675);
PAINT MONO (-4024 3675);
DISPLAY INVISIBLE (-4024 3675);
FORCEPROP 2 LAST $XRERR ?
J 0
(-4024 3675);
DISPLAY 0.638298 (-4024 3675);
PAINT MONO (-4024 3675);
DISPLAY INVISIBLE (-4024 3675);
FORCEPROP 2 LAST $XRERR ?
J 0
(-4024 3675);
DISPLAY 0.638298 (-4024 3675);
PAINT MONO (-4024 3675);
DISPLAY INVISIBLE (-4024 3675);
FORCEPROP 2 LAST $XRERR ?
J 0
(-4024 3675);
DISPLAY 0.638298 (-4024 3675);
PAINT MONO (-4024 3675);
DISPLAY INVISIBLE (-4024 3675);
FORCEPROP 2 LAST $XR0 143 
J 0
(-3880 3675);
DISPLAY 0.638298 (-3880 3675);
PAINT MONO (-3880 3675);
FORCEADD OFFPAGE..5
(-3625 3575);
FORCEPROP 1 LAST COMMENT_BODY TRUE
J 0
(-3525 3500);
DISPLAY 0.872340 (-3525 3500);
PAINT GREEN (-3525 3500);
DISPLAY INVISIBLE (-3525 3500);
FORCEPROP 1 LAST OFFPAGE TRUE
J 0
(-3300 3450);
DISPLAY 0.872340 (-3300 3450);
PAINT GREEN (-3300 3450);
DISPLAY INVISIBLE (-3300 3450);
FORCEPROP 2 LAST PATH I126
J 0
(-3575 3650);
DISPLAY 1.021277 (-3575 3650);
PAINT ORANGE (-3575 3650);
DISPLAY INVISIBLE (-3575 3650);
FORCEPROP 2 LAST CDS_LIB mstr_standard
J 0
(-3625 3575);
PAINT ORANGE (-3625 3575);
DISPLAY INVISIBLE (-3625 3575);
FORCEPROP 2 LAST $XR0 119 
J 0
(-3880 3575);
DISPLAY 0.638298 (-3880 3575);
PAINT MONO (-3880 3575);
FORCEADD CONN12_C73564003..1
(-2175 3675);
FORCEPROP 0 LAST BOM_COST SB
J 0
(-2475 4225);
DISPLAY 1.021277 (-2475 4225);
PAINT ORANGE (-2475 4225);
DISPLAY INVISIBLE (-2475 4225);
FORCEPROP 1 LAST PATH I128
J 0
(-2175 3975);
PAINT GREEN (-2175 3975);
DISPLAY INVISIBLE (-2175 3975);
FORCEPROP 2 LAST CDS_LIB mstr_conn
J 0
(-2175 3675);
PAINT ORANGE (-2175 3675);
DISPLAY INVISIBLE (-2175 3675);
FORCEPROP 2 LAST SEC 1
J 0
(-2475 4075);
DISPLAY 0.680851 (-2475 4075);
PAINT MONO (-2475 4075);
DISPLAY INVISIBLE (-2475 4075);
FORCEPROP 2 LAST SEC_TYPE PIP
J 0
(-2475 4075);
DISPLAY 1.021277 (-2475 4075);
PAINT ORANGE (-2475 4075);
DISPLAY INVISIBLE (-2475 4075);
FORCEPROP 0 LAST ROOM SB
J 0
(-2475 4125);
DISPLAY 1.021277 (-2475 4125);
PAINT ORANGE (-2475 4125);
DISPLAY INVISIBLE (-2475 4125);
FORCEPROP 1 LAST PACK_TYPE PIP
J 0
(-2475 4075);
PAINT SKYBLUE (-2475 4075);
DISPLAY INVISIBLE (-2475 4075);
FORCEPROP 2 LASTPIN (-2525 3575) $PN 9
J 2
(-2535 3585);
DISPLAY 0.617021 (-2535 3585);
PAINT ORANGE (-2535 3585);
FORCEPROP 2 LASTPIN (-2525 3525) $PN 11
J 2
(-2535 3535);
DISPLAY 0.617021 (-2535 3535);
PAINT ORANGE (-2535 3535);
FORCEPROP 2 LASTPIN (-2525 3625) $PN 7
J 2
(-2535 3635);
DISPLAY 0.617021 (-2535 3635);
PAINT ORANGE (-2535 3635);
FORCEPROP 2 LASTPIN (-2525 3725) $PN 3
J 2
(-2535 3735);
DISPLAY 0.617021 (-2535 3735);
PAINT ORANGE (-2535 3735);
FORCEPROP 2 LASTPIN (-2525 3775) $PN 1
J 2
(-2535 3785);
DISPLAY 0.617021 (-2535 3785);
PAINT ORANGE (-2535 3785);
FORCEPROP 2 LASTPIN (-2525 3675) $PN 5
J 2
(-2535 3685);
DISPLAY 0.617021 (-2535 3685);
PAINT ORANGE (-2535 3685);
FORCEPROP 2 LASTPIN (-1825 3625) $PN 8
J 0
(-1815 3635);
DISPLAY 0.617021 (-1815 3635);
PAINT ORANGE (-1815 3635);
FORCEPROP 2 LASTPIN (-1825 3575) $PN 10
J 0
(-1815 3585);
DISPLAY 0.617021 (-1815 3585);
PAINT ORANGE (-1815 3585);
FORCEPROP 2 LASTPIN (-1825 3525) $PN 12
J 0
(-1815 3535);
DISPLAY 0.617021 (-1815 3535);
PAINT ORANGE (-1815 3535);
FORCEPROP 2 LASTPIN (-1825 3675) $PN 6
J 0
(-1815 3685);
DISPLAY 0.617021 (-1815 3685);
PAINT ORANGE (-1815 3685);
FORCEPROP 2 LASTPIN (-1825 3725) $PN 4
J 0
(-1815 3735);
DISPLAY 0.617021 (-1815 3735);
PAINT ORANGE (-1815 3735);
FORCEPROP 2 LASTPIN (-1825 3775) $PN 2
J 0
(-1815 3785);
DISPLAY 0.617021 (-1815 3785);
PAINT ORANGE (-1815 3785);
FORCEPROP 1 LAST MATERIAL CONN
J 0
(-2475 3975);
DISPLAY 0.617021 (-2475 3975);
PAINT SKYBLUE (-2475 3975);
FORCEPROP 1 LAST PART_NUMBER C73564-003
J 0
(-2475 3375);
DISPLAY 0.617021 (-2475 3375);
PAINT BLUE (-2475 3375);
FORCEPROP 1 LAST LOCATION J9G1
J 0
(-2475 4025);
DISPLAY 0.617021 (-2475 4025);
PAINT AQUA (-2475 4025);
FORCEADD OFFPAGE..2
(850 3725);
FORCEPROP 1 LAST COMMENT_BODY TRUE
J 0
(805 3630);
DISPLAY 0.872340 (805 3630);
PAINT GREEN (805 3630);
DISPLAY INVISIBLE (805 3630);
FORCEPROP 1 LAST OFFPAGE TRUE
J 0
(1175 3600);
DISPLAY 0.872340 (1175 3600);
PAINT GREEN (1175 3600);
DISPLAY INVISIBLE (1175 3600);
FORCEPROP 2 LAST PATH I129
J 0
(900 3800);
DISPLAY 1.021277 (900 3800);
PAINT ORANGE (900 3800);
DISPLAY INVISIBLE (900 3800);
FORCEPROP 2 LAST CDS_LIB mstr_standard
J 0
(850 3725);
PAINT ORANGE (850 3725);
DISPLAY INVISIBLE (850 3725);
FORCEPROP 2 LAST $XR0 121 
J 0
(1039 3725);
DISPLAY 0.638298 (1039 3725);
PAINT MONO (1039 3725);
FORCEADD RES..2
(-200 4025);
FORCEPROP 2 LAST CDS_LIB mstr_discrete
J 0
(-200 4025);
PAINT ORANGE (-200 4025);
DISPLAY INVISIBLE (-200 4025);
FORCEPROP 2 LAST CDS_LOCATION R7C10
J 0
(-155 4150);
DISPLAY 0.617021 (-155 4150);
PAINT AQUA (-155 4150);
DISPLAY INVISIBLE (-155 4150);
FORCEPROP 2 LAST BOM_COST SB
J 0
(-150 4200);
PAINT ORANGE (-150 4200);
DISPLAY INVISIBLE (-150 4200);
FORCEPROP 1 LAST PATH I13
J 0
(-150 4200);
DISPLAY 1.319149 (-150 4200);
PAINT GREEN (-150 4200);
DISPLAY INVISIBLE (-150 4200);
FORCEPROP 2 LAST SEC 1
J 0
(-150 4250);
DISPLAY 0.936170 (-150 4250);
PAINT MONO (-150 4250);
DISPLAY INVISIBLE (-150 4250);
FORCEPROP 0 LAST NO_XNET_CONNECTION 1
J 0
(-150 4275);
PAINT MONO (-150 4275);
DISPLAY INVISIBLE (-150 4275);
FORCEPROP 2 LAST SEC_TYPE 0402
J 0
(-150 4275);
DISPLAY 1.021277 (-150 4275);
PAINT ORANGE (-150 4275);
DISPLAY INVISIBLE (-150 4275);
FORCEPROP 2 LAST ROOM SB
J 0
(-150 4200);
PAINT ORANGE (-150 4200);
DISPLAY INVISIBLE (-150 4200);
FORCEPROP 1 LASTPIN (-200 3925) $PN 2
J 0
(-195 3935);
DISPLAY 0.617021 (-195 3935);
PAINT MONO (-195 3935);
FORCEPROP 1 LASTPIN (-200 4125) $PN 1
J 0
(-195 4087);
DISPLAY 0.617021 (-195 4087);
PAINT MONO (-195 4087);
FORCEPROP 1 LAST WATTAGE 1/16W
J 0
(-160 4000);
DISPLAY 0.617021 (-160 4000);
PAINT SKYBLUE (-160 4000);
FORCEPROP 1 LAST MATERIAL CHIP
J 0
(-160 3950);
DISPLAY 0.617021 (-160 3950);
PAINT SKYBLUE (-160 3950);
FORCEPROP 1 LAST PACK_TYPE 0402
J 0
(-160 3850);
DISPLAY 0.617021 (-160 3850);
PAINT SKYBLUE (-160 3850);
FORCEPROP 1 LAST TOLERANCE 1%
J 0
(-155 4050);
DISPLAY 0.617021 (-155 4050);
PAINT SKYBLUE (-155 4050);
FORCEPROP 1 LAST VALUE 20.0K
J 0
(-155 4100);
DISPLAY 0.617021 (-155 4100);
PAINT SKYBLUE (-155 4100);
FORCEPROP 1 LAST PART_NUMBER G21796-040
J 0
(-160 3900);
DISPLAY 0.617021 (-160 3900);
PAINT BLUE (-160 3900);
FORCEPROP 1 LAST LOCATION R7C10
J 0
(-155 4150);
DISPLAY 0.617021 (-155 4150);
PAINT AQUA (-155 4150);
FORCEADD CAP_A..1
(-125 3450);
FORCEPROP 2 LAST CDS_LOCATION C7C19
J 0
(-75 3550);
DISPLAY 0.617021 (-75 3550);
PAINT AQUA (-75 3550);
DISPLAY INVISIBLE (-75 3550);
FORCEPROP 2 LAST CDS_LIB dev_discrete
J 0
(-125 3450);
PAINT ORANGE (-125 3450);
DISPLAY INVISIBLE (-125 3450);
FORCEPROP 2 LAST BOM_COST SB
J 0
(-75 3650);
PAINT ORANGE (-75 3650);
DISPLAY INVISIBLE (-75 3650);
FORCEPROP 2 LAST CDS_SEC 1
J 0
(-75 3600);
PAINT ORANGE (-75 3600);
DISPLAY INVISIBLE (-75 3600);
FORCEPROP 2 LAST SEC_TYPE 0402V
J 0
(-75 3675);
DISPLAY 1.021277 (-75 3675);
PAINT ORANGE (-75 3675);
DISPLAY INVISIBLE (-75 3675);
FORCEPROP 2 LAST SEC 1
J 0
(-75 3650);
DISPLAY 0.936170 (-75 3650);
PAINT MONO (-75 3650);
DISPLAY INVISIBLE (-75 3650);
FORCEPROP 1 LAST PATH I14
J 0
(-75 3600);
DISPLAY 0.978723 (-75 3600);
PAINT WHITE (-75 3600);
DISPLAY INVISIBLE (-75 3600);
FORCEPROP 2 LAST ROOM SB
J 0
(-75 3500);
DISPLAY 1.361702 (-75 3500);
PAINT ORANGE (-75 3500);
DISPLAY INVISIBLE (-75 3500);
FORCEPROP 1 LASTPIN (-125 3550) $PN 1
J 0
(-115 3530);
DISPLAY 0.617021 (-115 3530);
PAINT MONO (-115 3530);
FORCEPROP 1 LASTPIN (-125 3350) $PN 2
J 0
(-115 3330);
DISPLAY 0.617021 (-115 3330);
PAINT MONO (-115 3330);
FORCEPROP 1 LAST MATERIAL X6S
J 0
(-75 3350);
DISPLAY 0.617021 (-75 3350);
PAINT SKYBLUE (-75 3350);
FORCEPROP 1 LAST VOLTAGE 6.3V
J 0
(-75 3450);
DISPLAY 0.617021 (-75 3450);
PAINT SKYBLUE (-75 3450);
FORCEPROP 1 LAST PACK_TYPE 0402V
J 0
(-75 3250);
DISPLAY 0.617021 (-75 3250);
PAINT SKYBLUE (-75 3250);
FORCEPROP 1 LAST TOLERANCE 10%
J 0
(-75 3400);
DISPLAY 0.617021 (-75 3400);
PAINT SKYBLUE (-75 3400);
FORCEPROP 1 LAST VALUE 1.0UF
J 0
(-75 3500);
DISPLAY 0.617021 (-75 3500);
PAINT SKYBLUE (-75 3500);
FORCEPROP 1 LAST PART_NUMBER D97712-004
J 0
(-75 3300);
DISPLAY 0.617021 (-75 3300);
PAINT BLUE (-75 3300);
FORCEPROP 1 LAST LOCATION C7C19
J 0
(-75 3550);
DISPLAY 0.617021 (-75 3550);
PAINT AQUA (-75 3550);
FORCEADD RES..2
R 2
(-275 3450);
FORCEPROP 2 LAST CDS_LIB mstr_discrete
R 3
J 0
(-275 3450);
PAINT ORANGE (-275 3450);
DISPLAY INVISIBLE (-275 3450);
FORCEPROP 2 LAST SEC 1
J 0
(-325 3675);
DISPLAY 0.680851 (-325 3675);
PAINT MONO (-325 3675);
DISPLAY INVISIBLE (-325 3675);
FORCEPROP 2 LAST SEC_TYPE 0402
J 0
(-325 3675);
DISPLAY 1.021277 (-325 3675);
PAINT ORANGE (-325 3675);
DISPLAY INVISIBLE (-325 3675);
FORCEPROP 1 LAST PATH I15
J 2
(-325 3625);
DISPLAY 0.978723 (-325 3625);
PAINT WHITE (-325 3625);
DISPLAY INVISIBLE (-325 3625);
FORCEPROP 2 LAST BOM_COST SB
R 3
J 0
(-475 3650);
PAINT ORANGE (-475 3650);
DISPLAY INVISIBLE (-475 3650);
FORCEPROP 2 LAST ROOM SB
J 2
(-320 3525);
DISPLAY 1.361702 (-320 3525);
PAINT ORANGE (-320 3525);
DISPLAY INVISIBLE (-320 3525);
FORCEPROP 1 LASTPIN (-275 3350) $PN 2
J 2
(-280 3360);
DISPLAY 0.617021 (-280 3360);
PAINT ORANGE (-280 3360);
FORCEPROP 1 LASTPIN (-275 3550) $PN 1
J 2
(-280 3512);
DISPLAY 0.617021 (-280 3512);
PAINT ORANGE (-280 3512);
FORCEPROP 1 LAST WATTAGE 1/16W
J 2
(-315 3425);
DISPLAY 0.617021 (-315 3425);
PAINT SKYBLUE (-315 3425);
FORCEPROP 1 LAST MATERIAL CHIP
J 2
(-315 3375);
DISPLAY 0.617021 (-315 3375);
PAINT SKYBLUE (-315 3375);
FORCEPROP 1 LAST PACK_TYPE 0402
J 2
(-315 3275);
DISPLAY 0.617021 (-315 3275);
PAINT SKYBLUE (-315 3275);
FORCEPROP 1 LAST TOLERANCE 1%
J 2
(-320 3475);
DISPLAY 0.617021 (-320 3475);
PAINT SKYBLUE (-320 3475);
FORCEPROP 1 LAST VALUE 1.00K
J 2
(-320 3525);
DISPLAY 0.617021 (-320 3525);
PAINT SKYBLUE (-320 3525);
FORCEPROP 1 LAST PART_NUMBER G21796-026
J 2
(-315 3325);
DISPLAY 0.617021 (-315 3325);
PAINT BLUE (-315 3325);
FORCEPROP 1 LAST LOCATION R1U63
J 2
(-320 3575);
DISPLAY 0.617021 (-320 3575);
PAINT AQUA (-320 3575);
FORCEADD GND..1
(-275 3125);
FORCEPROP 3 LASTPIN (-275 3175) SIG_NAME GND\g
J 0
(-265 3185);
DISPLAY 0.659574 (-265 3185);
PAINT MONO (-265 3185);
DISPLAY INVISIBLE (-265 3185);
FORCEPROP 1 LAST HDL_POWER GND
J 0
(-275 3275);
DISPLAY 0.978723 (-275 3275);
PAINT GREEN (-275 3275);
DISPLAY INVISIBLE (-275 3275);
FORCEPROP 1 LAST BODY_TYPE PLUMBING
J 0
(-320 3082);
DISPLAY 0.340426 (-320 3082);
PAINT GREEN (-320 3082);
DISPLAY INVISIBLE (-320 3082);
FORCEPROP 2 LAST CDS_LIB mstr_symbols
J 0
(-275 3125);
DISPLAY 1.319149 (-275 3125);
PAINT ORANGE (-275 3125);
DISPLAY INVISIBLE (-275 3125);
FORCEPROP 2 LAST BOM_COST SB
J 0
(-325 3200);
PAINT ORANGE (-325 3200);
DISPLAY INVISIBLE (-325 3200);
FORCEPROP 1 LAST PATH I16
J 0
(-200 3125);
DISPLAY 1.170213 (-200 3125);
PAINT GREEN (-200 3125);
DISPLAY INVISIBLE (-200 3125);
FORCEPROP 1 LAST SIZE 1B
J 0
(-200 3075);
DISPLAY 0.978723 (-200 3075);
PAINT GREEN (-200 3075);
DISPLAY INVISIBLE (-200 3075);
FORCEPROP 2 LAST ROOM WBG_HEADERS_BIOS
J 0
(-650 3200);
PAINT ORANGE (-650 3200);
DISPLAY INVISIBLE (-650 3200);
FORCEPROP 1 LAST VOLTAGE 0
J 0
(-275 3125);
PAINT SKYBLUE (-275 3125);
DISPLAY INVISIBLE (-275 3125);
FORCEADD OFFPAGE..2
(475 2175);
FORCEPROP 1 LAST COMMENT_BODY TRUE
J 0
(430 2080);
DISPLAY 1.170213 (430 2080);
PAINT GREEN (430 2080);
DISPLAY INVISIBLE (430 2080);
FORCEPROP 1 LAST OFFPAGE TRUE
J 0
(800 2050);
PAINT GREEN (800 2050);
DISPLAY INVISIBLE (800 2050);
FORCEPROP 2 LAST BOM_COST SB
J 0
(675 2225);
PAINT ORANGE (675 2225);
DISPLAY INVISIBLE (675 2225);
FORCEPROP 2 LAST PATH I17
J 0
(675 2225);
PAINT MONO (675 2225);
DISPLAY INVISIBLE (675 2225);
FORCEPROP 2 LAST ROOM WBG_HEADERS_BIOS
J 0
(250 2250);
PAINT ORANGE (250 2250);
DISPLAY INVISIBLE (250 2250);
FORCEPROP 2 LAST CDS_LIB mstr_standard
J 0
(475 2175);
PAINT ORANGE (475 2175);
DISPLAY INVISIBLE (475 2175);
FORCEPROP 2 LAST $XR0 121 
J 0
(664 2175);
DISPLAY 0.638298 (664 2175);
PAINT MONO (664 2175);
FORCEADD RES..2
(-275 2425);
FORCEPROP 2 LAST CDS_LIB mstr_discrete
J 0
(-275 2425);
PAINT ORANGE (-275 2425);
DISPLAY INVISIBLE (-275 2425);
FORCEPROP 2 LAST CDS_LOCATION R3N4
J 0
(-230 2550);
DISPLAY 0.617021 (-230 2550);
PAINT AQUA (-230 2550);
DISPLAY INVISIBLE (-230 2550);
FORCEPROP 2 LAST BOM_COST SB
J 0
(-225 2600);
PAINT ORANGE (-225 2600);
DISPLAY INVISIBLE (-225 2600);
FORCEPROP 2 LAST CDS_SEC 1
J 0
(-225 2650);
DISPLAY 1.404255 (-225 2650);
PAINT ORANGE (-225 2650);
DISPLAY INVISIBLE (-225 2650);
FORCEPROP 2 LAST $SEC 1
J 0
(-225 2650);
DISPLAY 0.936170 (-225 2650);
PAINT MONO (-225 2650);
DISPLAY INVISIBLE (-225 2650);
FORCEPROP 1 LAST PATH I19
J 0
(-225 2600);
DISPLAY 1.319149 (-225 2600);
PAINT GREEN (-225 2600);
DISPLAY INVISIBLE (-225 2600);
FORCEPROP 0 LAST NO_XNET_CONNECTION 1
J 0
(-225 2675);
PAINT MONO (-225 2675);
DISPLAY INVISIBLE (-225 2675);
FORCEPROP 2 LAST ROOM SB
J 0
(-225 2600);
PAINT ORANGE (-225 2600);
DISPLAY INVISIBLE (-225 2600);
FORCEPROP 1 LASTPIN (-275 2325) $PN 2
J 0
(-270 2335);
DISPLAY 0.617021 (-270 2335);
PAINT MONO (-270 2335);
FORCEPROP 1 LASTPIN (-275 2525) $PN 1
J 0
(-270 2487);
DISPLAY 0.617021 (-270 2487);
PAINT MONO (-270 2487);
FORCEPROP 1 LAST WATTAGE 1/16W
J 0
(-235 2400);
DISPLAY 0.617021 (-235 2400);
PAINT SKYBLUE (-235 2400);
FORCEPROP 1 LAST MATERIAL CHIP
J 0
(-235 2350);
DISPLAY 0.617021 (-235 2350);
PAINT SKYBLUE (-235 2350);
FORCEPROP 1 LAST PACK_TYPE 0402
J 0
(-235 2250);
DISPLAY 0.617021 (-235 2250);
PAINT SKYBLUE (-235 2250);
FORCEPROP 1 LAST TOLERANCE 1%
J 0
(-230 2450);
DISPLAY 0.617021 (-230 2450);
PAINT SKYBLUE (-230 2450);
FORCEPROP 1 LAST VALUE 20.0K
J 0
(-230 2500);
DISPLAY 0.617021 (-230 2500);
PAINT SKYBLUE (-230 2500);
FORCEPROP 1 LAST PART_NUMBER G21796-040
J 0
(-235 2300);
DISPLAY 0.617021 (-235 2300);
PAINT BLUE (-235 2300);
FORCEPROP 1 LAST LOCATION R3N4
J 0
(-230 2550);
DISPLAY 0.617021 (-230 2550);
PAINT AQUA (-230 2550);
FORCEADD CAP_A..1
(-275 1975);
FORCEPROP 2 LAST CDS_LIB dev_discrete
J 0
(-275 1975);
PAINT ORANGE (-275 1975);
DISPLAY INVISIBLE (-275 1975);
FORCEPROP 1 LAST PATH I20
J 0
(-225 2125);
DISPLAY 0.978723 (-225 2125);
PAINT WHITE (-225 2125);
DISPLAY INVISIBLE (-225 2125);
FORCEPROP 2 LAST SEC 1
J 0
(-225 2175);
DISPLAY 0.936170 (-225 2175);
PAINT MONO (-225 2175);
DISPLAY INVISIBLE (-225 2175);
FORCEPROP 2 LAST SEC_TYPE 0402V
J 0
(-225 2200);
DISPLAY 1.021277 (-225 2200);
PAINT ORANGE (-225 2200);
DISPLAY INVISIBLE (-225 2200);
FORCEPROP 2 LAST CDS_SEC 1
J 0
(-225 2125);
PAINT ORANGE (-225 2125);
DISPLAY INVISIBLE (-225 2125);
FORCEPROP 2 LAST BOM_COST SB
J 0
(-225 2125);
PAINT ORANGE (-225 2125);
DISPLAY INVISIBLE (-225 2125);
FORCEPROP 2 LAST CDS_LOCATION C3N32
J 0
(-225 2075);
DISPLAY 0.617021 (-225 2075);
PAINT AQUA (-225 2075);
DISPLAY INVISIBLE (-225 2075);
FORCEPROP 2 LAST ROOM SB
J 0
(-225 2125);
PAINT ORANGE (-225 2125);
DISPLAY INVISIBLE (-225 2125);
FORCEPROP 1 LASTPIN (-275 1875) $PN 2
J 0
(-265 1855);
DISPLAY 0.617021 (-265 1855);
PAINT MONO (-265 1855);
FORCEPROP 1 LASTPIN (-275 2075) $PN 1
J 0
(-265 2055);
DISPLAY 0.617021 (-265 2055);
PAINT MONO (-265 2055);
FORCEPROP 1 LAST MATERIAL X6S
J 0
(-225 1875);
DISPLAY 0.617021 (-225 1875);
PAINT SKYBLUE (-225 1875);
FORCEPROP 1 LAST VOLTAGE 6.3V
J 0
(-225 1975);
DISPLAY 0.617021 (-225 1975);
PAINT SKYBLUE (-225 1975);
FORCEPROP 1 LAST PACK_TYPE 0402V
J 0
(-225 1775);
DISPLAY 0.617021 (-225 1775);
PAINT SKYBLUE (-225 1775);
FORCEPROP 1 LAST TOLERANCE 10%
J 0
(-225 1925);
DISPLAY 0.617021 (-225 1925);
PAINT SKYBLUE (-225 1925);
FORCEPROP 1 LAST VALUE 1.0UF
J 0
(-225 2025);
DISPLAY 0.617021 (-225 2025);
PAINT SKYBLUE (-225 2025);
FORCEPROP 1 LAST PART_NUMBER D97712-004
J 0
(-225 1825);
DISPLAY 0.617021 (-225 1825);
PAINT BLUE (-225 1825);
FORCEPROP 1 LAST LOCATION C3N32
J 0
(-225 2075);
DISPLAY 0.617021 (-225 2075);
PAINT AQUA (-225 2075);
FORCEADD GND..1
(-275 1775);
FORCEPROP 3 LASTPIN (-275 1825) SIG_NAME GND\g
J 0
(-265 1835);
DISPLAY 0.659574 (-265 1835);
PAINT MONO (-265 1835);
DISPLAY INVISIBLE (-265 1835);
FORCEPROP 1 LAST HDL_POWER GND
J 0
(-275 1925);
DISPLAY 1.170213 (-275 1925);
PAINT GREEN (-275 1925);
DISPLAY INVISIBLE (-275 1925);
FORCEPROP 1 LAST BODY_TYPE PLUMBING
J 0
(-320 1732);
DISPLAY 0.340426 (-320 1732);
PAINT GREEN (-320 1732);
DISPLAY INVISIBLE (-320 1732);
FORCEPROP 2 LAST CDS_LIB mstr_symbols
J 0
(-275 1775);
PAINT ORANGE (-275 1775);
DISPLAY INVISIBLE (-275 1775);
FORCEPROP 2 LAST BOM_COST SB
J 0
(-325 1850);
PAINT ORANGE (-325 1850);
DISPLAY INVISIBLE (-325 1850);
FORCEPROP 1 LAST PATH I21
J 0
(-200 1775);
DISPLAY 1.170213 (-200 1775);
PAINT GREEN (-200 1775);
DISPLAY INVISIBLE (-200 1775);
FORCEPROP 1 LAST SIZE 1B
J 0
(-200 1725);
DISPLAY 1.170213 (-200 1725);
PAINT GREEN (-200 1725);
DISPLAY INVISIBLE (-200 1725);
FORCEPROP 2 LAST ROOM WBG_HEADERS_BIOS
J 0
(-650 1850);
PAINT ORANGE (-650 1850);
DISPLAY INVISIBLE (-650 1850);
FORCEPROP 1 LAST VOLTAGE 0
J 0
(-275 1775);
PAINT SKYBLUE (-275 1775);
DISPLAY INVISIBLE (-275 1775);
FORCEADD RES..2
(-2875 4225);
FORCEPROP 2 LAST CDS_LIB mstr_discrete
J 0
(-2875 4225);
PAINT MONO (-2875 4225);
DISPLAY INVISIBLE (-2875 4225);
FORCEPROP 2 LAST CDS_LOCATION R7C13
J 0
(-2830 4350);
DISPLAY 0.617021 (-2830 4350);
PAINT AQUA (-2830 4350);
DISPLAY INVISIBLE (-2830 4350);
FORCEPROP 2 LAST SEC_TYPE 0402
J 0
(-2825 4450);
DISPLAY 1.021277 (-2825 4450);
PAINT ORANGE (-2825 4450);
DISPLAY INVISIBLE (-2825 4450);
FORCEPROP 2 LAST BOM_COST SB
J 0
(-2825 4400);
PAINT ORANGE (-2825 4400);
DISPLAY INVISIBLE (-2825 4400);
FORCEPROP 2 LAST SEC 1
J 0
(-2825 4450);
PAINT MONO (-2825 4450);
DISPLAY INVISIBLE (-2825 4450);
FORCEPROP 1 LAST PATH I67
J 0
(-2825 4400);
DISPLAY 0.978723 (-2825 4400);
PAINT WHITE (-2825 4400);
DISPLAY INVISIBLE (-2825 4400);
FORCEPROP 2 LAST ROOM SB
J 0
(-2830 4300);
DISPLAY 1.361702 (-2830 4300);
PAINT ORANGE (-2830 4300);
DISPLAY INVISIBLE (-2830 4300);
FORCEPROP 1 LASTPIN (-2875 4125) $PN 2
J 0
(-2870 4135);
DISPLAY 0.617021 (-2870 4135);
PAINT ORANGE (-2870 4135);
FORCEPROP 1 LASTPIN (-2875 4325) $PN 1
J 0
(-2870 4287);
DISPLAY 0.617021 (-2870 4287);
PAINT ORANGE (-2870 4287);
FORCEPROP 1 LAST WATTAGE 1/16W
J 0
(-2835 4200);
DISPLAY 0.617021 (-2835 4200);
PAINT SKYBLUE (-2835 4200);
FORCEPROP 1 LAST MATERIAL CHIP
J 0
(-2835 4150);
DISPLAY 0.617021 (-2835 4150);
PAINT SKYBLUE (-2835 4150);
FORCEPROP 1 LAST PACK_TYPE 0402
J 0
(-2835 4050);
DISPLAY 0.617021 (-2835 4050);
PAINT SKYBLUE (-2835 4050);
FORCEPROP 1 LAST TOLERANCE 1%
J 0
(-2830 4250);
DISPLAY 0.617021 (-2830 4250);
PAINT SKYBLUE (-2830 4250);
FORCEPROP 1 LAST VALUE 10.0K
J 0
(-2830 4300);
DISPLAY 0.617021 (-2830 4300);
PAINT SKYBLUE (-2830 4300);
FORCEPROP 1 LAST PART_NUMBER G21796-016
J 0
(-2835 4100);
DISPLAY 0.617021 (-2835 4100);
PAINT BLUE (-2835 4100);
FORCEPROP 1 LAST LOCATION R7C13
J 0
(-2830 4350);
DISPLAY 0.617021 (-2830 4350);
PAINT AQUA (-2830 4350);
FORCEADD P3V3_STBY..1
(-2875 4450);
FORCEPROP 3 LASTPIN (-2875 4400) SIG_NAME P3V3_STBY\g
J 0
(-2865 4410);
DISPLAY 0.659574 (-2865 4410);
PAINT MONO (-2865 4410);
DISPLAY INVISIBLE (-2865 4410);
FORCEPROP 1 LAST HDL_POWER P3V3_STBY
J 0
(-3175 4325);
DISPLAY 0.872340 (-3175 4325);
PAINT ORANGE (-3175 4325);
DISPLAY INVISIBLE (-3175 4325);
FORCEPROP 1 LAST BODY_TYPE PLUMBING
J 0
(-2920 4407);
DISPLAY 0.340426 (-2920 4407);
PAINT GREEN (-2920 4407);
DISPLAY INVISIBLE (-2920 4407);
FORCEPROP 1 LAST SIZE 1B
J 0
(-2830 4472);
DISPLAY 0.340426 (-2830 4472);
PAINT GREEN (-2830 4472);
DISPLAY INVISIBLE (-2830 4472);
FORCEPROP 2 LAST CDS_LIB mstr_symbols
J 0
(-2875 4450);
PAINT MONO (-2875 4450);
DISPLAY INVISIBLE (-2875 4450);
FORCEPROP 1 LAST PATH I68
J 0
(-2830 4452);
DISPLAY 0.340426 (-2830 4452);
PAINT GREEN (-2830 4452);
DISPLAY INVISIBLE (-2830 4452);
FORCEPROP 1 LAST VOLTAGE 3.3V
J 0
(-2920 4407);
DISPLAY 0.340426 (-2920 4407);
PAINT SKYBLUE (-2920 4407);
DISPLAY INVISIBLE (-2920 4407);
FORCEADD RES..2
(-2875 3300);
FORCEPROP 2 LAST CDS_LIB mstr_discrete
R 3
J 0
(-2875 3300);
PAINT MONO (-2875 3300);
DISPLAY INVISIBLE (-2875 3300);
FORCEPROP 1 LAST PATH I69
J 0
(-2825 3475);
DISPLAY 0.978723 (-2825 3475);
PAINT WHITE (-2825 3475);
DISPLAY INVISIBLE (-2825 3475);
FORCEPROP 2 LAST SEC 1
J 0
(-2825 3525);
DISPLAY 0.680851 (-2825 3525);
PAINT MONO (-2825 3525);
DISPLAY INVISIBLE (-2825 3525);
FORCEPROP 2 LAST SEC_TYPE 0402
J 0
(-2825 3525);
DISPLAY 1.021277 (-2825 3525);
PAINT ORANGE (-2825 3525);
DISPLAY INVISIBLE (-2825 3525);
FORCEPROP 2 LAST BOM_COST SB
R 3
J 0
(-2700 3250);
PAINT ORANGE (-2700 3250);
DISPLAY INVISIBLE (-2700 3250);
FORCEPROP 2 LAST ROOM SB
J 0
(-2830 3375);
DISPLAY 1.361702 (-2830 3375);
PAINT ORANGE (-2830 3375);
DISPLAY INVISIBLE (-2830 3375);
FORCEPROP 1 LASTPIN (-2875 3200) $PN 2
J 0
(-2870 3210);
DISPLAY 0.617021 (-2870 3210);
PAINT ORANGE (-2870 3210);
FORCEPROP 1 LASTPIN (-2875 3400) $PN 1
J 0
(-2870 3362);
DISPLAY 0.617021 (-2870 3362);
PAINT ORANGE (-2870 3362);
FORCEPROP 1 LAST WATTAGE 1/16W
J 0
(-2835 3275);
DISPLAY 0.617021 (-2835 3275);
PAINT SKYBLUE (-2835 3275);
FORCEPROP 1 LAST MATERIAL CHIP
J 0
(-2835 3225);
DISPLAY 0.617021 (-2835 3225);
PAINT SKYBLUE (-2835 3225);
FORCEPROP 1 LAST PACK_TYPE 0402
J 0
(-2835 3125);
DISPLAY 0.617021 (-2835 3125);
PAINT SKYBLUE (-2835 3125);
FORCEPROP 1 LAST TOLERANCE 1%
J 0
(-2830 3325);
DISPLAY 0.617021 (-2830 3325);
PAINT SKYBLUE (-2830 3325);
FORCEPROP 1 LAST VALUE 1.00K
J 0
(-2830 3375);
DISPLAY 0.617021 (-2830 3375);
PAINT SKYBLUE (-2830 3375);
FORCEPROP 1 LAST PART_NUMBER G21796-026
J 0
(-2835 3175);
DISPLAY 0.617021 (-2835 3175);
PAINT BLUE (-2835 3175);
FORCEPROP 1 LAST LOCATION R1U64
J 0
(-2830 3425);
DISPLAY 0.617021 (-2830 3425);
PAINT AQUA (-2830 3425);
FORCEADD GND..1
(-2875 3025);
FORCEPROP 3 LASTPIN (-2875 3075) SIG_NAME GND\g
J 0
(-2865 3085);
DISPLAY 0.659574 (-2865 3085);
PAINT MONO (-2865 3085);
DISPLAY INVISIBLE (-2865 3085);
FORCEPROP 1 LAST HDL_POWER GND
J 0
(-2875 3175);
DISPLAY 0.851064 (-2875 3175);
PAINT GREEN (-2875 3175);
DISPLAY INVISIBLE (-2875 3175);
FORCEPROP 1 LAST BODY_TYPE PLUMBING
J 0
(-2920 2982);
DISPLAY 0.340426 (-2920 2982);
PAINT GREEN (-2920 2982);
DISPLAY INVISIBLE (-2920 2982);
FORCEPROP 2 LAST CDS_LIB mstr_symbols
J 0
(-2875 3025);
PAINT MONO (-2875 3025);
DISPLAY INVISIBLE (-2875 3025);
FORCEPROP 1 LAST SIZE 1B
J 0
(-2800 2975);
DISPLAY 0.851064 (-2800 2975);
PAINT GREEN (-2800 2975);
DISPLAY INVISIBLE (-2800 2975);
FORCEPROP 1 LAST PATH I70
J 0
(-2800 3025);
DISPLAY 0.872340 (-2800 3025);
PAINT AQUA (-2800 3025);
DISPLAY INVISIBLE (-2800 3025);
FORCEPROP 2 LAST BOM_COST SB
J 0
(-2925 3100);
PAINT ORANGE (-2925 3100);
DISPLAY INVISIBLE (-2925 3100);
FORCEPROP 2 LAST ROOM WBG_HEADERS_BIOS
J 0
(-3250 3100);
PAINT ORANGE (-3250 3100);
DISPLAY INVISIBLE (-3250 3100);
FORCEPROP 1 LAST VOLTAGE 0
J 0
(-2875 3025);
PAINT SKYBLUE (-2875 3025);
DISPLAY INVISIBLE (-2875 3025);
FORCEADD P3V3_RTC_STBY..1
(-200 4225);
FORCEPROP 3 LASTPIN (-200 4175) SIG_NAME P3V3_RTC_STBY\g
J 0
(-190 4185);
DISPLAY 0.659574 (-190 4185);
PAINT MONO (-190 4185);
DISPLAY INVISIBLE (-190 4185);
FORCEPROP 1 LAST HDL_POWER P3V3_RTC_STBY
J 1
(-200 4275);
DISPLAY 0.872340 (-200 4275);
PAINT GREEN (-200 4275);
DISPLAY INVISIBLE (-200 4275);
FORCEPROP 1 LAST BODY_TYPE PLUMBING
J 0
(-245 4182);
DISPLAY 0.340426 (-245 4182);
PAINT GREEN (-245 4182);
DISPLAY INVISIBLE (-245 4182);
FORCEPROP 1 LAST PATH I78
J 0
(-150 4250);
DISPLAY 0.872340 (-150 4250);
PAINT AQUA (-150 4250);
DISPLAY INVISIBLE (-150 4250);
FORCEPROP 2 LAST CDS_LIB mstr_symbols
J 0
(-200 4225);
PAINT ORANGE (-200 4225);
DISPLAY INVISIBLE (-200 4225);
FORCEPROP 2 LAST BOM_COST SB
J 0
(-200 4375);
PAINT MONO (-200 4375);
DISPLAY INVISIBLE (-200 4375);
FORCEPROP 2 LAST ROOM SB_DECOUPLING
J 0
(-200 4325);
DISPLAY 1.361702 (-200 4325);
PAINT WHITE (-200 4325);
DISPLAY INVISIBLE (-200 4325);
FORCEPROP 1 LAST VOLTAGE 3.3V
J 0
(-245 4182);
DISPLAY 0.340426 (-245 4182);
PAINT SKYBLUE (-245 4182);
DISPLAY INVISIBLE (-245 4182);
FORCEADD P3V3_RTC_STBY..1
(-275 2675);
FORCEPROP 3 LASTPIN (-275 2625) SIG_NAME P3V3_RTC_STBY\g
J 0
(-265 2635);
DISPLAY 0.659574 (-265 2635);
PAINT MONO (-265 2635);
DISPLAY INVISIBLE (-265 2635);
FORCEPROP 1 LAST HDL_POWER P3V3_RTC_STBY
J 1
(-275 2725);
DISPLAY 0.872340 (-275 2725);
PAINT GREEN (-275 2725);
DISPLAY INVISIBLE (-275 2725);
FORCEPROP 1 LAST BODY_TYPE PLUMBING
J 0
(-320 2632);
DISPLAY 0.340426 (-320 2632);
PAINT GREEN (-320 2632);
DISPLAY INVISIBLE (-320 2632);
FORCEPROP 2 LAST BOM_COST SB
J 0
(-275 2825);
PAINT MONO (-275 2825);
DISPLAY INVISIBLE (-275 2825);
FORCEPROP 2 LAST CDS_LIB mstr_symbols
J 0
(-275 2675);
PAINT ORANGE (-275 2675);
DISPLAY INVISIBLE (-275 2675);
FORCEPROP 1 LAST PATH I79
J 0
(-225 2700);
DISPLAY 0.872340 (-225 2700);
PAINT AQUA (-225 2700);
DISPLAY INVISIBLE (-225 2700);
FORCEPROP 2 LAST ROOM SB_DECOUPLING
J 0
(-275 2775);
DISPLAY 1.361702 (-275 2775);
PAINT WHITE (-275 2775);
DISPLAY INVISIBLE (-275 2775);
FORCEPROP 1 LAST VOLTAGE 3.3V
J 0
(-320 2632);
DISPLAY 0.340426 (-320 2632);
PAINT SKYBLUE (-320 2632);
DISPLAY INVISIBLE (-320 2632);
FORCEADD BOM_NOTE..1
(-4975 2350);
FORCEPROP 1 LAST COMMENT_BODY TRUE
J 0
(-4950 2450);
DISPLAY 0.978723 (-4950 2450);
PAINT ORANGE (-4950 2450);
DISPLAY INVISIBLE (-4950 2450);
FORCEPROP 2 LAST CDS_LIB mstr_symbols
J 0
(-4975 2350);
PAINT ORANGE (-4975 2350);
DISPLAY INVISIBLE (-4975 2350);
FORCEPROP 0 LAST L1 4 JUMPER HEADERS ADDED (IPN 634479-007) IN MOD FILE
J 0
(-5125 2200);
DISPLAY 0.808511 (-5125 2200);
PAINT ORANGE (-5125 2200);
FORCEADD CAD_NOTE..1
(-2200 3175);
FORCEPROP 1 LAST COMMENT_BODY TRUE
J 0
(-2175 3275);
DISPLAY 0.978723 (-2175 3275);
PAINT ORANGE (-2175 3275);
DISPLAY INVISIBLE (-2175 3275);
FORCEPROP 2 LAST CDS_LIB mstr_symbols
J 0
(-2200 3175);
PAINT ORANGE (-2200 3175);
DISPLAY INVISIBLE (-2200 3175);
FORCEPROP 0 LAST L1 PLACE TO THE RIGHT OF OTHER 2X6 HEADER
J 0
(-2350 3025);
DISPLAY 1.021277 (-2350 3025);
PAINT ORANGE (-2350 3025);
FORCEADD DESIGN_NOTE..1
(550 4375);
FORCEPROP 1 LAST COMMENT_BODY TRUE
J 0
(575 4475);
DISPLAY 0.978723 (575 4475);
PAINT ORANGE (575 4475);
DISPLAY INVISIBLE (575 4475);
FORCEPROP 2 LAST CDS_LIB mstr_symbols
J 0
(550 4375);
PAINT ORANGE (550 4375);
DISPLAY INVISIBLE (550 4375);
FORCEPROP 0 LAST L1 CMOS CLEAR JUMPER
J 0
(350 4250);
DISPLAY 1.021277 (350 4250);
PAINT ORANGE (350 4250);
FORCEADD DNS..2
(330 3445);
PAINT RED (330 3445);
FORCEPROP 1 LAST COMMENT_BODY TRUE
R 1
J 0
(405 3220);
DISPLAY 0.872340 (405 3220);
PAINT GREEN (405 3220);
DISPLAY INVISIBLE (405 3220);
FORCEPROP 2 LAST CDS_LIB mstr_misc
J 0
(330 3445);
PAINT ORANGE (330 3445);
DISPLAY INVISIBLE (330 3445);
FORCEADD INTEL_CORP_BPAGE..1
(2650 500);
FORCEPROP 1 LAST CDS_CON_LAST_MODIFIED Tue Dec 01 13:53:16 2015
J 0
(1225 825);
PAINT ORANGE (1225 825);
DISPLAY INVISIBLE (1225 825);
FORCEPROP 1 LAST CUSTOM_TXT_CDS <CURRENT_DESIGN_SHEET> OF <TOTAL_DESIGN_SHEETS>
J 0
(2150 525);
PAINT ORANGE (2150 525);
FORCEPROP 1 LAST CUSTOM_TXT_CDS <CON_LAST_MODIFIED>
J 0
(725 850);
PAINT ORANGE (725 850);
FORCEPROP 2 LAST CUSTOM_TXT_CDS <XR_PAGE_TITLE>
J 0
(-5240 5750);
DISPLAY 0.638298 (-5240 5750);
PAINT PINK (-5240 5750);
DISPLAY INVISIBLE (-5240 5750);
FORCEPROP 2 LAST CDS_XR_PAGE_TITLE CR-137 : @BASEBOARD_FAB2_LIB.BASEBOARD_FAB2(SCH_1):PAGE137
J 0
(-5240 5750);
DISPLAY 0.638298 (-5240 5750);
PAINT PINK (-5240 5750);
DISPLAY INVISIBLE (-5240 5750);
FORCEPROP 1 LAST COMMENT_BODY TRUE
J 0
(2662 512);
DISPLAY 0.468085 (2662 512);
PAINT GREEN (2662 512);
DISPLAY INVISIBLE (2662 512);
FORCEPROP 2 LAST PAGE_BORDER TRUE
J 0
(-5240 5750);
DISPLAY 0.851064 (-5240 5750);
PAINT PINK (-5240 5750);
DISPLAY INVISIBLE (-5240 5750);
FORCEPROP 2 LAST BOM_COST SB
J 0
(-5225 5800);
PAINT MONO (-5225 5800);
DISPLAY INVISIBLE (-5225 5800);
FORCEPROP 2 LAST CDS_LIB mstr_symbols
J 0
(2650 500);
PAINT MONO (2650 500);
DISPLAY INVISIBLE (2650 500);
FORCEPROP 2 LAST ROOM WBG_HEADERS_BIOS
J 0
(-5225 5800);
PAINT MONO (-5225 5800);
DISPLAY INVISIBLE (-5225 5800);
FORCEPROP 1 LAST SCH_TITLE LBG HEADERS (3/3)
J 0
(-5300 550);
DISPLAY 1.212766 (-5300 550);
PAINT ORANGE (-5300 550);
FORCEPROP 1 LAST SCH_ADDRESS1 2200 Mission College Blvd.
J 0
(-1325 625);
DISPLAY 0.617021 (-1325 625);
PAINT GREEN (-1325 625);
FORCEPROP 1 LAST SCH_ADDRESS2 P.O. BOX 58119
J 0
(-1325 575);
DISPLAY 0.617021 (-1325 575);
PAINT GREEN (-1325 575);
FORCEPROP 1 LAST SCH_ADDRESS3 Santa Clara, CA 95052-8119
J 0
(-1325 525);
DISPLAY 0.617021 (-1325 525);
PAINT GREEN (-1325 525);
FORCEPROP 1 LAST SCH_REV 2.420
J 0
(2400 650);
DISPLAY 0.978723 (2400 650);
PAINT YELLOW (2400 650);
FORCEPROP 1 LAST SCH_DEPT BESD
J 1
(-1800 600);
DISPLAY 1.212766 (-1800 600);
PAINT YELLOW (-1800 600);
FORCEPROP 1 LAST SCH_NUMBER H4694802
J 0
(1350 650);
DISPLAY 1.212766 (1350 650);
PAINT YELLOW (1350 650);
FORCEADD DESIGN_NOTE..1
(-3975 3375);
FORCEPROP 1 LAST COMMENT_BODY TRUE
J 0
(-3950 3475);
DISPLAY 0.978723 (-3950 3475);
PAINT ORANGE (-3950 3475);
DISPLAY INVISIBLE (-3950 3475);
FORCEPROP 2 LAST CDS_LIB mstr_symbols
J 0
(-3975 3375);
PAINT MONO (-3975 3375);
DISPLAY INVISIBLE (-3975 3375);
FORCEPROP 0 LAST L1 IE DEBUG
J 0
(-4175 3250);
DISPLAY 1.021277 (-4175 3250);
PAINT ORANGE (-4175 3250);
FORCEADD DESIGN_NOTE..1
(-3975 4350);
FORCEPROP 1 LAST COMMENT_BODY TRUE
J 0
(-3950 4450);
DISPLAY 0.978723 (-3950 4450);
PAINT ORANGE (-3950 4450);
DISPLAY INVISIBLE (-3950 4450);
FORCEPROP 2 LAST CDS_LIB mstr_symbols
J 0
(-3975 4350);
PAINT MONO (-3975 4350);
DISPLAY INVISIBLE (-3975 4350);
FORCEPROP 0 LAST L1 BMC RESET JUMPER
J 0
(-4175 4225);
DISPLAY 1.021277 (-4175 4225);
PAINT ORANGE (-4175 4225);
WIRE 16 -1 (-275 3200)(-275 3175);
WIRE 16 -1 (-275 3200)(-125 3200);
WIRE 16 -1 (-275 3350)(-275 3200);
WIRE 16 -1 (325 3200)(-125 3200);
WIRE 16 -1 (-125 3200)(-125 3350);
WIRE 16 -1 (325 3350)(325 3200);
WIRE 16 -1 (-275 1825)(-275 1875);
WIRE 16 -1 (-2875 4325)(-2875 4400);
WIRE 16 -1 (-200 4175)(-200 4125);
WIRE 16 -1 (-275 2625)(-275 2525);
WIRE 16 -1 (-2875 3075)(-2875 3200);
WIRE 16 -1 (-3575 3625)(-2525 3625);
FORCEPROP 2 LAST SIG_NAME TP_IE_DEBUG_MODE
J 0
(-3510 3635);
DISPLAY 0.617021 (-3510 3635);
PAINT ORANGE (-3510 3635);
FORCEPROP 2 LASTPROP $XRERR UNIQUE?
J 0
(-3815 3625);
DISPLAY 0.638298 (-3815 3625);
PAINT MONO (-3815 3625);
DISPLAY INVISIBLE (-3815 3625);
WIRE 16 -1 (-2875 3575)(-2525 3575);
WIRE 16 -1 (-2875 4125)(-2875 3575);
WIRE 16 -1 (-3575 3575)(-2875 3575);
FORCEPROP 2 LAST SIG_NAME FM_UART_PRES_N
J 0
(-3510 3585);
DISPLAY 0.617021 (-3510 3585);
PAINT ORANGE (-3510 3585);
WIRE 16 -1 (-3575 3675)(-2525 3675);
FORCEPROP 2 LAST SIG_NAME FM_BMC_DISABLE
J 0
(-3510 3685);
DISPLAY 0.617021 (-3510 3685);
PAINT ORANGE (-3510 3685);
WIRE 16 -1 (-4125 4100)(-3400 4100);
WIRE 16 -1 (-4175 3975)(-3350 3975);
WIRE 16 -1 (-4175 4200)(-4175 3975);
WIRE 16 -1 (-3350 3975)(-3350 4200);
WIRE 16 -1 (-3350 4200)(-4175 4200);
WIRE 16 -1 (-3575 3775)(-2525 3775);
FORCEPROP 2 LAST SIG_NAME TP_BMC_DISABLE
J 0
(-3510 3785);
DISPLAY 0.617021 (-3510 3785);
PAINT ORANGE (-3510 3785);
FORCEPROP 2 LASTPROP $XRERR UNIQUE?
J 0
(-3815 3775);
DISPLAY 0.638298 (-3815 3775);
PAINT MONO (-3815 3775);
DISPLAY INVISIBLE (-3815 3775);
WIRE 16 -1 (-5100 2000)(-1700 2000);
WIRE 16 -1 (-2900 2100)(-2900 1500);
WIRE 16 -1 (575 4175)(575 4025);
WIRE 16 -1 (1525 4100)(1525 4200);
WIRE 16 -1 (1525 4200)(350 4200);
WIRE 16 -1 (1525 4000)(1525 4100);
WIRE 16 -1 (350 4000)(1525 4000);
WIRE 16 -1 (350 4200)(350 4100);
WIRE 16 -1 (350 4100)(1525 4100);
WIRE 16 -1 (350 4100)(350 4000);
WIRE 16 -1 (-275 2175)(-275 2075);
WIRE 16 -1 (-275 2325)(-275 2175);
WIRE 16 -1 (425 2175)(-275 2175);
FORCEPROP 2 LAST SIG_NAME RST_SRTCRST_N
J 0
(-35 2185);
DISPLAY 0.617021 (-35 2185);
PAINT ORANGE (-35 2185);
WIRE 16 -1 (-3950 4175)(-3950 4000);
WIRE 16 -1 (-275 3675)(-275 3550);
WIRE 16 -1 (-1825 3675)(-275 3675);
FORCEPROP 2 LAST SIG_NAME PD_RST_RTCRST_N
J 2
(-800 3685);
DISPLAY 0.617021 (-800 3685);
PAINT ORANGE (-800 3685);
FORCEPROP 2 LASTPROP $XRERR UNIQUE?
J 0
(-1040 3685);
DISPLAY 0.638298 (-1040 3685);
PAINT MONO (-1040 3685);
DISPLAY INVISIBLE (-1040 3685);
WIRE 16 -1 (-1825 3625)(-775 3625);
FORCEPROP 2 LAST SIG_NAME TP_JUMPER_BLOCK_2_8
J 2
(-800 3635);
DISPLAY 0.617021 (-800 3635);
PAINT ORANGE (-800 3635);
FORCEPROP 2 LASTPROP $XRERR UNIQUE?
J 0
(-745 3625);
DISPLAY 0.638298 (-745 3625);
PAINT MONO (-745 3625);
DISPLAY INVISIBLE (-745 3625);
WIRE 16 -1 (-1825 3575)(-775 3575);
FORCEPROP 2 LAST SIG_NAME TP_JUMPER_BLOCK_2_10
J 2
(-800 3585);
DISPLAY 0.617021 (-800 3585);
PAINT ORANGE (-800 3585);
FORCEPROP 2 LASTPROP $XRERR UNIQUE?
J 0
(-745 3575);
DISPLAY 0.638298 (-745 3575);
PAINT MONO (-745 3575);
DISPLAY INVISIBLE (-745 3575);
WIRE 16 -1 (-3950 3200)(-3950 3025);
WIRE 16 -1 (-3525 2100)(-3525 1500);
WIRE 16 -1 (-4125 3125)(-3400 3125);
WIRE 16 -1 (-5100 1750)(-1700 1750);
WIRE 16 -1 (-1675 2125)(-5125 2125);
WIRE 16 -1 (-1675 1450)(-1675 2125);
WIRE 16 -1 (-5125 2125)(-5125 1450);
WIRE 16 -1 (-5125 1450)(-1675 1450);
WIRE 16 -1 (-4475 2100)(-4475 1500);
WIRE 16 -1 (-1825 3775)(-775 3775);
FORCEPROP 2 LAST SIG_NAME TP_RST_RTCRST_N
J 2
(-800 3785);
DISPLAY 0.617021 (-800 3785);
PAINT ORANGE (-800 3785);
FORCEPROP 2 LASTPROP $XRERR UNIQUE?
J 0
(-745 3775);
DISPLAY 0.638298 (-745 3775);
PAINT MONO (-745 3775);
DISPLAY INVISIBLE (-745 3775);
WIRE 16 -1 (325 3550)(325 3725);
WIRE 16 -1 (325 3725)(800 3725);
FORCEPROP 2 LAST SIG_NAME RST_RTCRST_N
J 0
(440 3735);
DISPLAY 0.617021 (440 3735);
PAINT ORANGE (440 3735);
WIRE 16 -1 (-125 3550)(-125 3725);
WIRE 16 -1 (-125 3725)(325 3725);
WIRE 16 -1 (-200 3725)(-125 3725);
WIRE 16 -1 (-200 3725)(-200 3925);
WIRE 16 -1 (-1825 3725)(-200 3725);
WIRE 16 -1 (-1825 3525)(-775 3525);
FORCEPROP 2 LAST SIG_NAME TP_JUMPER_BLOCK_2_12
J 2
(-800 3535);
DISPLAY 0.617021 (-800 3535);
PAINT ORANGE (-800 3535);
FORCEPROP 2 LASTPROP $XRERR UNIQUE?
J 0
(-745 3525);
DISPLAY 0.638298 (-745 3525);
PAINT MONO (-745 3525);
DISPLAY INVISIBLE (-745 3525);
WIRE 16 -1 (-3350 3225)(-4175 3225);
WIRE 16 -1 (-3350 3000)(-3350 3225);
WIRE 16 -1 (-4175 3225)(-4175 3000);
WIRE 16 -1 (-4175 3000)(-3350 3000);
WIRE 16 -1 (-3575 3725)(-2525 3725);
FORCEPROP 2 LAST SIG_NAME FM_ROMA<0>
J 0
(-3510 3735);
DISPLAY 0.617021 (-3510 3735);
PAINT ORANGE (-3510 3735);
WIRE 16 -1 (-2875 3525)(-2525 3525);
WIRE 16 -1 (-2875 3400)(-2875 3525);
FORCEPROP 2 LAST SIG_NAME PD_IE_DEBUG_MODE
J 0
(-3135 3535);
DISPLAY 0.617021 (-3135 3535);
PAINT ORANGE (-3135 3535);
FORCEPROP 2 LASTPROP $XRERR UNIQUE?
J 0
(-3375 3535);
DISPLAY 0.638298 (-3375 3535);
PAINT MONO (-3375 3535);
DISPLAY INVISIBLE (-3375 3535);
DOT 1 (-2875 3575);
DOT 1 (-275 2175);
DOT 1 (-275 3200);
DOT 1 (-125 3200);
DOT 1 (-200 3725);
DOT 1 (-125 3725);
DOT 1 (325 3725);
DOT 1 (1525 4100);
DOT 1 (350 4100);
FORCENOTE
BMC HELD IN RESET
(-3925 4025) 0;
DISPLAY LEFT (-3925 4025);
DISPLAY 0.617021 (-3925 4025);
PAINT PURPLE (-3925 4025);
FORCENOTE
NORMAL<DEFAULT>
(-3925 4125) 0;
DISPLAY LEFT (-3925 4125);
DISPLAY 0.617021 (-3925 4125);
PAINT PURPLE (-3925 4125);
FORCENOTE
10-12
(-3100 1525) 0;
DISPLAY LEFT (-3100 1525);
DISPLAY 1.021277 (-3100 1525);
PAINT PURPLE (-3100 1525);
FORCENOTE
SMBUS UART NOT PRESENT
(-3925 3050) 0;
DISPLAY LEFT (-3925 3050);
DISPLAY 0.617021 (-3925 3050);
PAINT PURPLE (-3925 3050);
FORCENOTE
NORMAL<DEFAULT>
(-3925 3150) 0;
DISPLAY LEFT (-3925 3150);
DISPLAY 0.617021 (-3925 3150);
PAINT PURPLE (-3925 3150);
FORCENOTE
1-3
(-4625 1900) 0;
DISPLAY LEFT (-4625 1900);
DISPLAY 1.021277 (-4625 1900);
PAINT PURPLE (-4625 1900);
FORCENOTE
7-9
(-4625 1650) 0;
DISPLAY LEFT (-4625 1650);
DISPLAY 1.021277 (-4625 1650);
PAINT PURPLE (-4625 1650);
FORCENOTE
3-5
(-4625 1775) 0;
DISPLAY LEFT (-4625 1775);
DISPLAY 1.021277 (-4625 1775);
PAINT PURPLE (-4625 1775);
FORCENOTE
ROOM=SB
(-5079 842) 0;
DISPLAY LEFT (-5079 842);
DISPLAY 1.191489 (-5079 842);
PAINT PURPLE (-5079 842);
FORCENOTE
9-11
(-4625 1525) 0;
DISPLAY LEFT (-4625 1525);
DISPLAY 1.021277 (-4625 1525);
PAINT PURPLE (-4625 1525);
FORCENOTE
JUMPER LOCATION
(-5100 2025) 0;
DISPLAY LEFT (-5100 2025);
DISPLAY 1.021277 (-5100 2025);
PAINT PURPLE (-5100 2025);
FORCENOTE
3-5
(-4125 4025) 0;
DISPLAY LEFT (-4125 4025);
DISPLAY 0.617021 (-4125 4025);
PAINT PURPLE (-4125 4025);
FORCENOTE
1-3
(-4125 4125) 0;
DISPLAY LEFT (-4125 4125);
DISPLAY 0.617021 (-4125 4125);
PAINT PURPLE (-4125 4125);
FORCENOTE
9-11
(-4125 3050) 0;
DISPLAY LEFT (-4125 3050);
DISPLAY 0.617021 (-4125 3050);
PAINT PURPLE (-4125 3050);
FORCENOTE
7-9
(-4125 3150) 0;
DISPLAY LEFT (-4125 3150);
DISPLAY 0.617021 (-4125 3150);
PAINT PURPLE (-4125 3150);
FORCENOTE
SYSTEM BEHAVIOR
(-4425 2025) 0;
DISPLAY LEFT (-4425 2025);
DISPLAY 1.021277 (-4425 2025);
PAINT PURPLE (-4425 2025);
FORCENOTE
NORMAL FUNCTIONALITY
(-4425 1650) 0;
DISPLAY LEFT (-4425 1650);
DISPLAY 1.021277 (-4425 1650);
PAINT PURPLE (-4425 1650);
FORCENOTE
SMBUS UART NOT PRESENT
(-4425 1525) 0;
DISPLAY LEFT (-4425 1525);
DISPLAY 1.021277 (-4425 1525);
PAINT PURPLE (-4425 1525);
FORCENOTE
NORMAL FUNCTIONALITY
(-4425 1900) 0;
DISPLAY LEFT (-4425 1900);
DISPLAY 1.021277 (-4425 1900);
PAINT PURPLE (-4425 1900);
FORCENOTE
BMC HELD IN RESET
(-4425 1775) 0;
DISPLAY LEFT (-4425 1775);
DISPLAY 1.021277 (-4425 1775);
PAINT PURPLE (-4425 1775);
FORCENOTE
8-10
(-3100 1650) 0;
DISPLAY LEFT (-3100 1650);
DISPLAY 1.021277 (-3100 1650);
PAINT PURPLE (-3100 1650);
FORCENOTE
2-4
(-3100 1900) 0;
DISPLAY LEFT (-3100 1900);
DISPLAY 1.021277 (-3100 1900);
PAINT PURPLE (-3100 1900);
FORCENOTE
4-6
(-3100 1775) 0;
DISPLAY LEFT (-3100 1775);
DISPLAY 1.021277 (-3100 1775);
PAINT PURPLE (-3100 1775);
FORCENOTE
NOT USED
(-2800 1525) 0;
DISPLAY LEFT (-2800 1525);
DISPLAY 1.021277 (-2800 1525);
PAINT PURPLE (-2800 1525);
FORCENOTE
NOT USED
(-2800 1650) 0;
DISPLAY LEFT (-2800 1650);
DISPLAY 1.021277 (-2800 1650);
PAINT PURPLE (-2800 1650);
FORCENOTE
JUMPER LOCATION
(-3500 2025) 0;
DISPLAY LEFT (-3500 2025);
DISPLAY 1.021277 (-3500 2025);
PAINT PURPLE (-3500 2025);
FORCENOTE
SYSTEM BEHAVIOR
(-2800 2025) 0;
DISPLAY LEFT (-2800 2025);
DISPLAY 1.021277 (-2800 2025);
PAINT PURPLE (-2800 2025);
FORCENOTE
CLEAR RTC REGISTERS
(-2800 1775) 0;
DISPLAY LEFT (-2800 1775);
DISPLAY 1.021277 (-2800 1775);
PAINT PURPLE (-2800 1775);
FORCENOTE
NORMAL FUNCTIONALITY
(-2800 1900) 0;
DISPLAY LEFT (-2800 1900);
DISPLAY 1.021277 (-2800 1900);
PAINT PURPLE (-2800 1900);
FORCENOTE
4-6
(400 4050) 0;
DISPLAY LEFT (400 4050);
DISPLAY 0.617021 (400 4050);
PAINT PURPLE (400 4050);
FORCENOTE
CLEAR RTC REGISTERS
(625 4050) 0;
DISPLAY LEFT (625 4050);
DISPLAY 0.617021 (625 4050);
PAINT PURPLE (625 4050);
FORCENOTE
2-4
(400 4125) 0;
DISPLAY LEFT (400 4125);
DISPLAY 0.617021 (400 4125);
PAINT PURPLE (400 4125);
FORCENOTE
NORMAL RTC RESET (DEFAULT)
(625 4125) 0;
DISPLAY LEFT (625 4125);
DISPLAY 0.617021 (625 4125);
PAINT PURPLE (625 4125);
QUIT
